(kicad_pcb
	(version 20260206)
	(generator "pcbnew")
	(generator_version "10.0")
	(general
		(thickness 1.6)
		(legacy_teardrops no)
	)
	(paper "A4")
	(title_block
		(title "Wiwynn_Tioga_Pass_MB.brd")
		(comment 1 "Tioga Pass / footprint 3319 of 4770 (J6L2), pads 244-291 of 291")
	)
	(layers
		(0 "F.Cu" signal "TOP")
		(4 "In1.Cu" signal "L2GND")
		(6 "In2.Cu" signal "L3")
		(8 "In3.Cu" signal "L4GND")
		(10 "In4.Cu" signal "L5")
		(12 "In5.Cu" signal "L6GND")
		(14 "In6.Cu" signal "L7VCC")
		(16 "In7.Cu" signal "L8VCC")
		(18 "In8.Cu" signal "L9GND")
		(20 "In9.Cu" signal "L10")
		(22 "In10.Cu" signal "L11GND")
		(24 "In11.Cu" signal "L12")
		(26 "In12.Cu" signal "L13GND")
		(2 "B.Cu" signal "BOTTOM")
		(9 "F.Adhes" user "F.Adhesive")
		(11 "B.Adhes" user "B.Adhesive")
		(13 "F.Paste" user "Package Geometry/Pastemask Top")
		(15 "B.Paste" user "Package Geometry/Pastemask Bottom")
		(5 "F.SilkS" user "Ref Des/Silkscreen Top")
		(7 "B.SilkS" user "Ref Des/Silkscreen Bottom")
		(1 "F.Mask" user "Board Geometry/Soldermask Top")
		(3 "B.Mask" user "Board Geometry/Soldermask Bottom")
		(17 "Dwgs.User" user "User.Drawings")
		(19 "Cmts.User" user "User.Comments")
		(21 "Eco1.User" user "User.Eco1")
		(23 "Eco2.User" user "User.Eco2")
		(25 "Edge.Cuts" user "Board Geometry/Outline")
		(27 "Margin" user)
		(31 "F.CrtYd" user "Package Geometry/Place Bound Top")
		(29 "B.CrtYd" user "Package Geometry/Place Bound Bottom")
		(35 "F.Fab" user "Ref Des/Assembly Top")
		(33 "B.Fab" user "Ref Des/Assembly Bottom")
	)
	(footprint ""
		(layer "B.Cu")
		(at 194.700398 -142.477236 90)
		(property "Reference" "J6L2"
			(at 2.276348 38.21811 0)
			(unlocked yes)
			(layer "B.SilkS")
			(effects
				(font
					(size 0.7874 0.5842)
					(thickness 0.1524)
				)
				(justify left mirror)
			)
		)
		(property "Value" ""
			(at 0 0 90)
			(layer "B.Fab")
			(effects
				(font
					(size 1.27 1.27)
				)
				(justify mirror)
			)
		)
		(duplicate_pad_numbers_are_jumpers no)
		(pad "241" smd rect
			(at -4.59994 86.700106 270)
			(size 1.8034 0.508)
			(layers "B.Cu" "B.Mask" "B.Paste")
			(net "GND")
		)
		(pad "242" smd rect
			(at -4.59994 87.54999 270)
			(size 1.8034 0.508)
			(layers "B.Cu" "B.Mask" "B.Paste")
			(net "M_E_DQ<33>")
		)
		(pad "243" smd rect
			(at -4.59994 88.399874 270)
			(size 1.8034 0.508)
			(layers "B.Cu" "B.Mask" "B.Paste")
			(net "GND")
		)
		(pad "244" smd rect
			(at -4.59994 89.250012 270)
			(size 1.8034 0.508)
			(layers "B.Cu" "B.Mask" "B.Paste")
			(net "M_E_DQS_DN<4>")
		)
		(pad "245" smd rect
			(at -4.59994 90.099896 270)
			(size 1.8034 0.508)
			(layers "B.Cu" "B.Mask" "B.Paste")
			(net "M_E_DQS_DP<4>")
		)
		(pad "246" smd rect
			(at -4.59994 90.950034 270)
			(size 1.8034 0.508)
			(layers "B.Cu" "B.Mask" "B.Paste")
			(net "GND")
		)
		(pad "247" smd rect
			(at -4.59994 91.799918 270)
			(size 1.8034 0.508)
			(layers "B.Cu" "B.Mask" "B.Paste")
			(net "M_E_DQ<39>")
		)
		(pad "248" smd rect
			(at -4.59994 92.650056 270)
			(size 1.8034 0.508)
			(layers "B.Cu" "B.Mask" "B.Paste")
			(net "GND")
		)
		(pad "249" smd rect
			(at -4.59994 93.49994 270)
			(size 1.8034 0.508)
			(layers "B.Cu" "B.Mask" "B.Paste")
			(net "M_E_DQ<35>")
		)
		(pad "250" smd rect
			(at -4.59994 94.350078 270)
			(size 1.8034 0.508)
			(layers "B.Cu" "B.Mask" "B.Paste")
			(net "GND")
		)
		(pad "251" smd rect
			(at -4.59994 95.199962 270)
			(size 1.8034 0.508)
			(layers "B.Cu" "B.Mask" "B.Paste")
			(net "M_E_DQ<45>")
		)
		(pad "252" smd rect
			(at -4.59994 96.0501 270)
			(size 1.8034 0.508)
			(layers "B.Cu" "B.Mask" "B.Paste")
			(net "GND")
		)
		(pad "253" smd rect
			(at -4.59994 96.899984 270)
			(size 1.8034 0.508)
			(layers "B.Cu" "B.Mask" "B.Paste")
			(net "M_E_DQ<41>")
		)
		(pad "254" smd rect
			(at -4.59994 97.750122 270)
			(size 1.8034 0.508)
			(layers "B.Cu" "B.Mask" "B.Paste")
			(net "GND")
		)
		(pad "255" smd rect
			(at -4.59994 98.600006 270)
			(size 1.8034 0.508)
			(layers "B.Cu" "B.Mask" "B.Paste")
			(net "M_E_DQS_DN<5>")
		)
		(pad "256" smd rect
			(at -4.59994 99.44989 270)
			(size 1.8034 0.508)
			(layers "B.Cu" "B.Mask" "B.Paste")
			(net "M_E_DQS_DP<5>")
		)
		(pad "257" smd rect
			(at -4.59994 100.300028 270)
			(size 1.8034 0.508)
			(layers "B.Cu" "B.Mask" "B.Paste")
			(net "GND")
		)
		(pad "258" smd rect
			(at -4.59994 101.149912 270)
			(size 1.8034 0.508)
			(layers "B.Cu" "B.Mask" "B.Paste")
			(net "M_E_DQ<47>")
		)
		(pad "259" smd rect
			(at -4.59994 102.00005 270)
			(size 1.8034 0.508)
			(layers "B.Cu" "B.Mask" "B.Paste")
			(net "GND")
		)
		(pad "260" smd rect
			(at -4.59994 102.849934 270)
			(size 1.8034 0.508)
			(layers "B.Cu" "B.Mask" "B.Paste")
			(net "M_E_DQ<43>")
		)
		(pad "261" smd rect
			(at -4.59994 103.700072 270)
			(size 1.8034 0.508)
			(layers "B.Cu" "B.Mask" "B.Paste")
			(net "GND")
		)
		(pad "262" smd rect
			(at -4.59994 104.549956 270)
			(size 1.8034 0.508)
			(layers "B.Cu" "B.Mask" "B.Paste")
			(net "M_E_DQ<53>")
		)
		(pad "263" smd rect
			(at -4.59994 105.400094 270)
			(size 1.8034 0.508)
			(layers "B.Cu" "B.Mask" "B.Paste")
			(net "GND")
		)
		(pad "264" smd rect
			(at -4.59994 106.249978 270)
			(size 1.8034 0.508)
			(layers "B.Cu" "B.Mask" "B.Paste")
			(net "M_E_DQ<49>")
		)
		(pad "265" smd rect
			(at -4.59994 107.100116 270)
			(size 1.8034 0.508)
			(layers "B.Cu" "B.Mask" "B.Paste")
			(net "GND")
		)
		(pad "266" smd rect
			(at -4.59994 107.95 270)
			(size 1.8034 0.508)
			(layers "B.Cu" "B.Mask" "B.Paste")
			(net "M_E_DQS_DN<6>")
		)
		(pad "267" smd rect
			(at -4.59994 108.799884 270)
			(size 1.8034 0.508)
			(layers "B.Cu" "B.Mask" "B.Paste")
			(net "M_E_DQS_DP<6>")
		)
		(pad "268" smd rect
			(at -4.59994 109.650022 270)
			(size 1.8034 0.508)
			(layers "B.Cu" "B.Mask" "B.Paste")
			(net "GND")
		)
		(pad "269" smd rect
			(at -4.59994 110.499906 270)
			(size 1.8034 0.508)
			(layers "B.Cu" "B.Mask" "B.Paste")
			(net "M_E_DQ<55>")
		)
		(pad "270" smd rect
			(at -4.59994 111.350044 270)
			(size 1.8034 0.508)
			(layers "B.Cu" "B.Mask" "B.Paste")
			(net "GND")
		)
		(pad "271" smd rect
			(at -4.59994 112.199928 270)
			(size 1.8034 0.508)
			(layers "B.Cu" "B.Mask" "B.Paste")
			(net "M_E_DQ<51>")
		)
		(pad "272" smd rect
			(at -4.59994 113.050066 270)
			(size 1.8034 0.508)
			(layers "B.Cu" "B.Mask" "B.Paste")
			(net "GND")
		)
		(pad "273" smd rect
			(at -4.59994 113.89995 270)
			(size 1.8034 0.508)
			(layers "B.Cu" "B.Mask" "B.Paste")
			(net "M_E_DQ<61>")
		)
		(pad "274" smd rect
			(at -4.59994 114.750088 270)
			(size 1.8034 0.508)
			(layers "B.Cu" "B.Mask" "B.Paste")
			(net "GND")
		)
		(pad "275" smd rect
			(at -4.59994 115.599972 270)
			(size 1.8034 0.508)
			(layers "B.Cu" "B.Mask" "B.Paste")
			(net "M_E_DQ<57>")
		)
		(pad "276" smd rect
			(at -4.59994 116.45011 270)
			(size 1.8034 0.508)
			(layers "B.Cu" "B.Mask" "B.Paste")
			(net "GND")
		)
		(pad "277" smd rect
			(at -4.59994 117.299994 270)
			(size 1.8034 0.508)
			(layers "B.Cu" "B.Mask" "B.Paste")
			(net "M_E_DQS_DN<7>")
		)
		(pad "278" smd rect
			(at -4.59994 118.149878 270)
			(size 1.8034 0.508)
			(layers "B.Cu" "B.Mask" "B.Paste")
			(net "M_E_DQS_DP<7>")
		)
		(pad "279" smd rect
			(at -4.59994 119.000016 270)
			(size 1.8034 0.508)
			(layers "B.Cu" "B.Mask" "B.Paste")
			(net "GND")
		)
		(pad "280" smd rect
			(at -4.59994 119.8499 270)
			(size 1.8034 0.508)
			(layers "B.Cu" "B.Mask" "B.Paste")
			(net "M_E_DQ<63>")
		)
		(pad "281" smd rect
			(at -4.59994 120.700038 270)
			(size 1.8034 0.508)
			(layers "B.Cu" "B.Mask" "B.Paste")
			(net "GND")
		)
		(pad "282" smd rect
			(at -4.59994 121.549922 270)
			(size 1.8034 0.508)
			(layers "B.Cu" "B.Mask" "B.Paste")
			(net "M_E_DQ<59>")
		)
		(pad "283" smd rect
			(at -4.59994 122.40006 270)
			(size 1.8034 0.508)
			(layers "B.Cu" "B.Mask" "B.Paste")
			(net "GND")
		)
		(pad "284" smd rect
			(at -4.59994 123.249944 270)
			(size 1.8034 0.508)
			(layers "B.Cu" "B.Mask" "B.Paste")
			(net "PVPP_DEF")
		)
		(pad "285" smd rect
			(at -4.59994 124.100082 270)
			(size 1.8034 0.508)
			(layers "B.Cu" "B.Mask" "B.Paste")
			(net "SMB_DDR_DEF_VPP_SDA")
		)
		(pad "286" smd rect
			(at -4.59994 124.949966 270)
			(size 1.8034 0.508)
			(layers "B.Cu" "B.Mask" "B.Paste")
			(net "PVPP_DEF")
		)
		(pad "287" smd rect
			(at -4.59994 125.800104 270)
			(size 1.8034 0.508)
			(layers "B.Cu" "B.Mask" "B.Paste")
			(net "PVPP_DEF")
		)
		(pad "288" smd rect
			(at -4.59994 126.649988 270)
			(size 1.8034 0.508)
			(layers "B.Cu" "B.Mask" "B.Paste")
			(net "PVPP_DEF")
		)
	)
)
